G04 ================== begin FILE IDENTIFICATION RECORD ==================*
G04 Layout Name:  17301-sa.brd*
G04 Film Name:    L3*
G04 File Format:  Gerber RS274X*
G04 File Origin:  Cadence Allegro 16.6-2015-S079*
G04 Origin Date:  Thu Jun 22 17:50:02 2017*
G04 *
G04 Layer:  VIA CLASS/L3*
G04 Layer:  PIN/L3*
G04 Layer:  ETCH/L3*
G04 Layer:  DRAWING FORMAT/LAYER_PCB_STORY*
G04 Layer:  DRAWING FORMAT/LAYER_L3*
G04 *
G04 Offset:    (0.00 0.00)*
G04 Mirror:    No*
G04 Mode:      Positive*
G04 Rotation:  0*
G04 FullContactRelief:  No*
G04 UndefLineWidth:     6.00*
G04 ================== end FILE IDENTIFICATION RECORD ====================*
%FSLAX35Y35*MOIN*%
%IR0*IPPOS*OFA0.00000B0.00000*MIA0B0*SFA1.00000B1.00000*%
%ADD14C,.02*%
%ADD12C,.022*%
%ADD13C,.034*%
%ADD15C,.071*%
%ADD11C,.146*%
%ADD10C,.182*%
%ADD16C,.01*%
%ADD17C,.006*%
%ADD18C,.0056*%
%ADD20C,.04404*%
%ADD21C,.04604*%
%ADD22C,.09504*%
%ADD19C,.11004*%
%ADD23C,.11704*%
G75*
%LPD*%
G75*
G36*
G01X214489Y85221D02*
X214318Y85334D01*
G03X211266Y82282I-1218J-1834D01*
G01X211379Y82111D01*
X209884Y80616D01*
X101678D01*
X92700Y71638D01*
X69409D01*
X63340Y65569D01*
G02X62606Y65599I-353J354D01*
G03X59502Y62495I-1678J-1426D01*
G02X59532Y61761I-324J-381D01*
G01X58906Y61135D01*
Y35114D01*
X60962Y33058D01*
Y29958D01*
X62549Y28371D01*
Y16855D01*
G03Y13223I5563J-1816D01*
G01Y3674D01*
X61879Y3004D01*
X3937D01*
G02X3004Y3937I0J933D01*
G01Y87402D01*
G02X3937Y88335I933J0D01*
G01X192914D01*
G03X197886Y93307I-1J4973D01*
G01Y94240D01*
X217500D01*
X218511Y93229D01*
Y89244D01*
X214489Y85221D01*
G37*
G36*
G01X183111Y62865D02*
X216771D01*
X221509Y58127D01*
X221528Y58080D01*
G03X227666Y56659I3569J1448D01*
G02X228430Y56541I334J-373D01*
G03X238865Y57279I5032J2987D01*
G01X266440D01*
X268252Y55467D01*
Y17121D01*
X258664Y7533D01*
X225352D01*
X222797Y10088D01*
X217823D01*
X217019Y9284D01*
G02X216169Y9697I-354J353D01*
G03X211154Y12007I-2882J342D01*
G02X210420I-367J339D01*
G03X206154I-2133J-1968D01*
G02X205420I-367J339D01*
G03X201154I-2133J-1968D01*
G02X200420I-367J339D01*
G03X196154I-2133J-1968D01*
G02X195420I-367J339D01*
G03X191154I-2133J-1968D01*
G02X190420I-367J339D01*
G03X186154I-2133J-1968D01*
G02X185420I-367J339D01*
G03X181154I-2133J-1968D01*
G02X180420I-367J339D01*
G03X176382Y12228I-2133J-1968D01*
G02X175554Y12606I-328J377D01*
G01Y38338D01*
X188977D01*
G03X193946Y43307I-1J4970D01*
G01Y45276D01*
G03X188977Y50246I-4970J0D01*
G01X175554D01*
Y51961D01*
G02X176382Y52339I500J1D01*
G03X180420Y52560I1905J2189D01*
G02X181154I367J-339D01*
G03X185420I2133J1968D01*
G02X186154I367J-339D01*
G03X190420I2133J1968D01*
G02X191154I367J-339D01*
G03X195420I2133J1968D01*
G02X196154I367J-339D01*
G03X200420I2133J1968D01*
G02X201154I367J-339D01*
G03X205420I2133J1968D01*
G02X206154I367J-339D01*
G03X210420I2133J1968D01*
G02X211154I367J-339D01*
G03Y56496I2133J1968D01*
G02X210420I-367J339D01*
G03X206154I-2133J-1968D01*
G02X205420I-367J339D01*
G03X201154I-2133J-1968D01*
G02X200420I-367J339D01*
G03X196154I-2133J-1968D01*
G02X195420I-367J339D01*
G03X191154I-2133J-1968D01*
G02X190420I-367J339D01*
G03X186154I-2133J-1968D01*
G02X185420I-367J339D01*
G03X181154I-2133J-1968D01*
G02X180420I-367J339D01*
G03X176382Y56717I-2133J-1968D01*
G02X175554Y57095I-328J377D01*
G01Y59091D01*
X178362Y61899D01*
X183111Y62865D01*
G37*
G36*
G01X315948Y26376D02*
X315995Y26522D01*
G03X313222Y29295I-2095J678D01*
G01X313076Y29248D01*
X308373Y33951D01*
X301235D01*
X274716Y7432D01*
X266324D01*
X264968Y8788D01*
Y11242D01*
X271611Y17885D01*
Y34826D01*
G02X272377Y35249I500J0D01*
G03Y38975I1174J1863D01*
G02X271611Y39398I-266J423D01*
G01Y60111D01*
X275119Y63619D01*
X290141D01*
X300559Y53201D01*
X323206D01*
X326188Y50219D01*
Y45956D01*
X326182Y45928D01*
G03Y44888I2242J-520D01*
G01X326188Y44860D01*
Y37159D01*
X331924Y31423D01*
Y29885D01*
X331771Y29821D01*
G03X333078Y25435I895J-2121D01*
G01X333207Y25459D01*
X335020Y23646D01*
Y18703D01*
X333283Y16966D01*
X326806D01*
X326743Y17123D01*
G03X324091Y18416I-2043J-823D01*
G01X323949Y18375D01*
X315948Y26376D01*
G37*
G36*
G01X537402Y3001D02*
G02X536466Y3937I0J936D01*
G01Y71063D01*
G03X534699Y75689I-6939J0D01*
G02X534717Y76375I372J333D01*
G03X535136Y81354I-2512J2719D01*
G03X532490Y82785I-2932J-2259D01*
G03X528544Y78551I-285J-3691D01*
G02X528046Y78001I-498J-50D01*
G01X515584D01*
Y78004D01*
X497050D01*
X494354Y80700D01*
Y81656D01*
X494345D01*
Y81925D01*
G02X495028Y82390I500J0D01*
G03Y91232I1743J4421D01*
G02X494345Y91697I-183J465D01*
G01Y114458D01*
X487155Y121648D01*
Y135032D01*
G02X487890Y135473I500J0D01*
G03X489753Y135121I1441J2519D01*
G03X491464Y136024I-422J2871D01*
G02X492198I367J-339D01*
G03X496464I2133J1968D01*
G02X497198I367J-339D01*
G03X501464I2133J1968D01*
G02X502198I367J-339D01*
G03Y139960I2133J1968D01*
G02X501464I-367J339D01*
G03X497198I-2133J-1968D01*
G02X496464I-367J339D01*
G03X492198I-2133J-1968D01*
G02X491464I-367J339D01*
G03X489753Y140863I-2133J-1968D01*
G03X487890Y140511I-422J-2871D01*
G02X487155Y140952I-235J441D01*
G01Y160890D01*
G03X490422Y166334I-2903J5444D01*
G01Y180114D01*
G03X487155Y185558I-6170J0D01*
G01Y200780D01*
G02X487890Y201221I500J0D01*
G03X489753Y200869I1441J2519D01*
G03X491464Y201772I-422J2871D01*
G02X492198I367J-339D01*
G03X496464I2133J1968D01*
G02X497198I367J-339D01*
G03X501464I2133J1968D01*
G02X502198I367J-339D01*
G03Y205708I2133J1968D01*
G02X501464I-367J339D01*
G03X497198I-2133J-1968D01*
G02X496464I-367J339D01*
G03X492198I-2133J-1968D01*
G02X491464I-367J339D01*
G03X489753Y206611I-2133J-1968D01*
G03X487890Y206259I-422J-2871D01*
G02X487155Y206700I-235J441D01*
G01Y231197D01*
X484489Y233863D01*
X313316D01*
X286642Y207189D01*
Y124642D01*
X286000Y124000D01*
X277626D01*
X276626Y125000D01*
Y252756D01*
G02X277559Y253689I933J0D01*
G01X561024D01*
G02X561957Y252756I0J-933D01*
G01Y106532D01*
X561960D01*
Y3937D01*
G02X561024Y3001I-936J0D01*
G01X537402D01*
G37*
G36*
G01X484218Y223121D02*
X328276D01*
X305887Y200732D01*
Y166958D01*
G02X305068Y166573I-500J0D01*
G03X302022Y166476I-1468J-1773D01*
G02X301669Y166485I-172J182D01*
G03X301578Y163224I-1669J-1585D01*
G02X301931Y163215I172J-182D01*
G03X305068Y163027I1669J1585D01*
G02X305887Y162642I319J-385D01*
G01Y142937D01*
G02X305086Y142538I-500J0D01*
G03X304911Y142658I-1388J-1837D01*
G02X304843Y143020I132J212D01*
G03X301527Y146169I-1842J1380D01*
G02X300867Y146187I-320J384D01*
G03X300773Y142731I-1567J-1687D01*
G02X301433Y142713I320J-384D01*
G03X301612Y142563I1566J1687D01*
G02X301737Y141903I-301J-399D01*
G03X305086Y138862I1963J-1203D01*
G02X305887Y138463I301J-399D01*
G01Y131059D01*
X302842Y128014D01*
X292611D01*
X289961Y130664D01*
Y162694D01*
X290171Y162728D01*
G03Y167272I-371J2272D01*
G01X289961Y167306D01*
Y206961D01*
X315105Y232105D01*
X484143D01*
X485728Y230520D01*
Y224631D01*
X484218Y223121D01*
G37*
G36*
G01X307989Y3004D02*
X307489Y3504D01*
G02X307776Y3956I500J0D01*
G03X309872Y5252I-4626J9824D01*
G03X312342Y8000I-6723J8527D01*
G01X324067D01*
X325200Y6866D01*
X345870D01*
G03X349672Y8088I1550J1702D01*
G02X350218Y8481I489J-104D01*
G03X349635Y12910I261J2287D01*
G01X349591Y12892D01*
X348500D01*
Y14500D01*
X345500Y17500D01*
X338211D01*
X336711Y19000D01*
Y31155D01*
X341403Y35847D01*
X348404D01*
G02X348892Y35237I0J-500D01*
G03X353188I2148J-484D01*
G02X353676Y35847I488J110D01*
G01X363455D01*
G03X366045I1295J1903D01*
G01X372980D01*
Y3937D01*
G02X372047Y3004I-933J0D01*
G01X307989D01*
G37*
G36*
G01X345927Y39386D02*
X344417Y40896D01*
Y70731D01*
X351675Y77989D01*
Y82872D01*
X352715Y87982D01*
X351675Y93081D01*
Y93680D01*
X351522Y93833D01*
X351338Y94736D01*
X349209Y96146D01*
X335896Y109459D01*
X335877Y109511D01*
G03X333714Y111674I-3387J-1224D01*
G01X333662Y111693D01*
X315170Y130185D01*
G02X315439Y131031I353J353D01*
G03X312779Y133691I-391J2269D01*
G02X311933Y133422I-493J84D01*
G01X311391Y133964D01*
Y143687D01*
G03Y146313I-1891J1313D01*
G01Y166542D01*
X313278Y168429D01*
X330464D01*
X330478Y168414D01*
X339845D01*
X342246Y166013D01*
Y140488D01*
X355583Y127151D01*
X477148D01*
X491593Y112706D01*
Y81600D01*
X489328Y79334D01*
X479058D01*
X468946Y89446D01*
Y91383D01*
G02X469803Y91733I500J0D01*
G03X469769Y94924I1642J1613D01*
G02X468908Y95215I-364J343D01*
G03X462008Y101426I-6900J-727D01*
G01X375971D01*
X370989Y96444D01*
Y41500D01*
X368875Y39386D01*
X366369D01*
G03X363131I-1619J-1636D01*
G01X345927D01*
G37*
G36*
G01X354596Y131158D02*
X344119Y141635D01*
Y166482D01*
X340080Y170521D01*
X334651D01*
X334650Y170520D01*
X314143D01*
X311507Y173156D01*
Y182370D01*
G03Y186286I-1007J1958D01*
G01Y203073D01*
X312972Y204538D01*
Y204606D01*
X324298Y215932D01*
X324474Y215776D01*
G03X327724Y219026I1526J1724D01*
G01X327568Y219202D01*
X329866Y221500D01*
X371321D01*
X378939Y213882D01*
X475510D01*
X477397Y211995D01*
Y205904D01*
G03X477198Y205708I1935J-2163D01*
G02X476464I-367J339D01*
G03X472198I-2133J-1968D01*
G02X471464I-367J339D01*
G03X467198I-2133J-1968D01*
G02X466464I-367J339D01*
G03X462198I-2133J-1968D01*
G02X461464I-367J339D01*
G03X457198I-2133J-1968D01*
G02X456464I-367J339D01*
G03X452198I-2133J-1968D01*
G02X451464I-367J339D01*
G03X447198I-2133J-1968D01*
G02X446464I-367J339D01*
G03X442198I-2133J-1968D01*
G02X441464I-367J339D01*
G03X437198I-2133J-1968D01*
G02X436464I-367J339D01*
G03Y201772I-2133J-1968D01*
G02X437198I367J-339D01*
G03X441464I2133J1968D01*
G02X442198I367J-339D01*
G03X446464I2133J1968D01*
G02X447198I367J-339D01*
G03X451464I2133J1968D01*
G02X452198I367J-339D01*
G03X456464I2133J1968D01*
G02X457198I367J-339D01*
G03X461464I2133J1968D01*
G02X462198I367J-339D01*
G03X466464I2133J1968D01*
G02X467198I367J-339D01*
G03X471464I2133J1968D01*
G02X472198I367J-339D01*
G03X476464I2133J1968D01*
G02X477198I367J-339D01*
G03X477397Y201576I2134J1967D01*
G01Y191081D01*
X473056Y186740D01*
X375428D01*
X372273Y183585D01*
Y182525D01*
X372254Y182479D01*
G03X371782Y180114I5698J-2367D01*
G01Y166334D01*
G03X377951Y160164I6170J0D01*
G01X476892D01*
X477246Y159811D01*
Y140011D01*
G03X477029Y139759I2087J-2017D01*
G02X476633I-198J153D01*
G03X472198Y139960I-2302J-1767D01*
G02X471464I-367J339D01*
G03X467198I-2133J-1968D01*
G02X466464I-367J339D01*
G03X462198I-2133J-1968D01*
G02X461464I-367J339D01*
G03X457198I-2133J-1968D01*
G02X456464I-367J339D01*
G03X452198I-2133J-1968D01*
G02X451464I-367J339D01*
G03X447198I-2133J-1968D01*
G02X446464I-367J339D01*
G03X442198I-2133J-1968D01*
G02X441464I-367J339D01*
G03X437198I-2133J-1968D01*
G02X436464I-367J339D01*
G03Y136024I-2133J-1968D01*
G02X437198I367J-339D01*
G03X441464I2133J1968D01*
G02X442198I367J-339D01*
G03X446464I2133J1968D01*
G02X447198I367J-339D01*
G03X451464I2133J1968D01*
G02X452198I367J-339D01*
G03X456464I2133J1968D01*
G02X457198I367J-339D01*
G03X461464I2133J1968D01*
G02X462198I367J-339D01*
G03X466464I2133J1968D01*
G02X467198I367J-339D01*
G03X471464I2133J1968D01*
G02X472198I367J-339D01*
G03X476633Y136225I2133J1968D01*
G02X477029I198J-153D01*
G03X477246Y135973I2304J1765D01*
G01Y132880D01*
X475524Y131158D01*
X354596D01*
G37*
%LPC*%
G75*
G36*
G01X206574Y88322D02*
G03X205926I-324J-381D01*
G02Y91678I-1426J1678D01*
G03X206574I324J381D01*
G02Y88322I1426J-1678D01*
G37*
G36*
G01X61986Y82272D02*
G03X62000Y81538I346J-361D01*
G02X59074Y81650I-1531J-1719D01*
G03X59066Y82053I-152J199D01*
G02X58952Y82139I1329J1880D01*
G03X58587Y82081I-156J-195D01*
G02X55024Y81739I-1920J1270D01*
G03X54310I-357J-350D01*
G02Y84963I-1643J1612D01*
G03X55024I357J350D01*
G02X57934Y85273I1643J-1612D01*
G03X58599Y85377I275J417D01*
G02X61986Y82272I1793J-1444D01*
G37*
G36*
G01X245357Y45888D02*
G03X244643I-357J-350D01*
G02Y49112I-1643J1612D01*
G03X245357I357J350D01*
G02Y45888I1643J-1612D01*
G37*
G36*
G01X217179Y39859D02*
G03X217844Y39468I494J79D01*
G02X216437Y36986I756J-2068D01*
G03X215761Y37356I-491J-94D01*
G02X213536Y37644I-854J2138D01*
G03X213186Y37592I-149J-201D01*
G02X209859Y37198I-1849J1371D01*
G03X209206Y37188I-321J-384D01*
G02X209153Y40672I-1531J1719D01*
G03X209806Y40682I321J384D01*
G02X212707Y40813I1531J-1719D01*
G03X213057Y40865I149J201D01*
G02X217179Y39859I1849J-1371D01*
G37*
G36*
G01X244857Y25388D02*
G03X244143I-357J-350D01*
G02Y28612I-1643J1612D01*
G03X244857I357J350D01*
G02Y25388I1643J-1612D01*
G37*
G36*
G01X227666Y17908D02*
G03X228430Y18026I334J373D01*
G02Y12052I5032J-2987D01*
G03X227666Y12170I-430J-255D01*
G02Y17908I-2569J2869D01*
G37*
G36*
G01X283682Y49659D02*
G03X283664Y49304I166J-186D01*
G02X280421Y46044I-1701J-1551D01*
G03X279763Y46054I-335J-371D01*
G02X276744Y49530I-1485J1759D01*
G03X276762Y49885I-166J186D01*
G02X276751Y52977I1700J1552D01*
G03X276741Y53656I-372J334D01*
G02X279950Y56953I1666J1589D01*
G03X280608Y56943I335J371D01*
G02X283804Y53644I1485J-1759D01*
G03X283814Y52965I372J-334D01*
G02X283682Y49659I-1666J-1589D01*
G37*
G36*
G01X518710Y211609D02*
G03X519474Y211727I334J373D01*
G02Y205753I5032J-2987D01*
G03X518710Y205871I-430J-255D01*
G02Y211609I-2569J2869D01*
G37*
G36*
G01Y145861D02*
G03X519474Y145979I334J373D01*
G02Y140005I5032J-2987D01*
G03X518710Y140123I-430J-255D01*
G02Y145861I-2569J2869D01*
G37*
G36*
G01X299319Y193552D02*
G03Y193198I176J-177D01*
G02X296077I-1621J-1635D01*
G03Y193552I-176J177D01*
G02X296232Y196961I1621J1634D01*
G03X296257Y197710I-319J386D01*
G02X296083Y200868I1583J1671D01*
G03X296076Y201521I-382J322D01*
G02X297928Y205340I1729J1520D01*
G03X298454Y205860I27J499D01*
G02X300631Y203657I2300J96D01*
G03X300105Y203137I-27J-499D01*
G02X299562Y201554I-2300J-96D01*
G03X299569Y200901I382J-322D01*
G02X299306Y197607I-1729J-1519D01*
G03X299281Y196858I319J-386D01*
G02X299319Y193552I-1583J-1671D01*
G37*
G36*
G01X322595Y149327D02*
G02X320217Y148428I-553J-2131D01*
G03X319916Y149194I-415J279D01*
G02X318795Y149824I522J2242D01*
G03X318081I-357J-350D01*
G02X314887Y153137I-1643J1612D01*
G03X314868Y153892I-337J369D01*
G02X314883Y157457I1464J1776D01*
G03Y158233I-315J388D01*
G02X314960Y161871I1449J1789D01*
G03Y162673I-298J401D01*
G02X317975Y166134I1372J1849D01*
G03X318689I357J350D01*
G02X321704Y162673I1643J-1612D01*
G03Y161871I298J-401D01*
G02X321781Y158233I-1372J-1849D01*
G03Y157457I315J-388D01*
G02X321883Y153967I-1449J-1789D01*
G03X321902Y153212I337J-369D01*
G02X322314Y150101I-1464J-1777D01*
G03X322595Y149327I407J-290D01*
G37*
G36*
G01X382327Y201914D02*
G03X381571Y201895I-370J-337D01*
G02Y205585I-2240J1845D01*
G03X382327Y205566I386J318D01*
G02X384331Y206452I2005J-1826D01*
G01X389331D01*
G02X391335Y205566I-1J-2712D01*
G03X392091Y205585I370J337D01*
G02X396571I2240J-1845D01*
G03X397327Y205566I386J318D01*
G02X399331Y206452I2005J-1826D01*
G01X404331D01*
G02X406335Y205566I-1J-2712D01*
G03X407091Y205585I370J337D01*
G02Y201895I2240J-1845D01*
G03X406335Y201914I-386J-318D01*
G02X404331Y201028I-2005J1826D01*
G01X399331D01*
G02X397327Y201914I1J2712D01*
G03X396571Y201895I-370J-337D01*
G02X392091I-2240J1845D01*
G03X391335Y201914I-386J-318D01*
G02X389331Y201028I-2005J1826D01*
G01X384331D01*
G02X382327Y201914I1J2712D01*
G37*
G36*
G01X417106Y149204D02*
G02X413956I-1575J1813D01*
G02X409980Y151017I-1575J1813D01*
G01Y151817D01*
G02X413956Y153630I2401J0D01*
G02X417106I1575J-1813D01*
G02X420256I1575J-1813D01*
G02X423406I1575J-1813D01*
G02X426556I1575J-1813D01*
G02X429706I1575J-1813D01*
G02X433682Y151817I1575J-1813D01*
G01Y151017D01*
G02X429706Y149204I-2401J0D01*
G02X426556I-1575J1813D01*
G02X423406I-1575J1813D01*
G02X420256I-1575J1813D01*
G02X417106I-1575J1813D01*
G37*
G36*
G01X382327Y136166D02*
G03X381571Y136147I-370J-337D01*
G02Y139837I-2240J1845D01*
G03X382327Y139818I386J318D01*
G02X384331Y140704I2005J-1826D01*
G01X389331D01*
G02X391335Y139818I-1J-2712D01*
G03X392091Y139837I370J337D01*
G02X396571I2240J-1845D01*
G03X397327Y139818I386J318D01*
G02X399331Y140704I2005J-1826D01*
G01X404331D01*
G02X406335Y139818I-1J-2712D01*
G03X407091Y139837I370J337D01*
G02Y136147I2240J-1845D01*
G03X406335Y136166I-386J-318D01*
G02X404331Y135280I-2005J1826D01*
G01X399331D01*
G02X397327Y136166I1J2712D01*
G03X396571Y136147I-370J-337D01*
G02X392091I-2240J1845D01*
G03X391335Y136166I-386J-318D01*
G02X389331Y135280I-2005J1826D01*
G01X384331D01*
G02X382327Y136166I1J2712D01*
G37*
G36*
G01X336643Y191888D02*
G02X333960Y195554I-1643J1612D01*
G03Y196446I-225J446D01*
G02Y200554I1040J2054D01*
G03Y201446I-225J446D01*
G02X336643Y205112I1040J2054D01*
G03X337357I357J350D01*
G02X340040Y201446I1643J-1612D01*
G03Y200554I225J-446D01*
G02Y196446I-1040J-2054D01*
G03Y195554I225J-446D01*
G02X337357Y191888I-1040J-2054D01*
G03X336643I-357J-350D01*
G37*
G54D20*
X222206Y41500D03*
X258088Y21787D03*
X322100Y26600D03*
X506868Y166599D03*
X358900Y23928D03*
X336238Y148951D03*
G54D21*
X281221Y33971D03*
X286638Y33917D03*
X304000Y213000D03*
X476600Y227250D03*
X326423Y183632D03*
X332000Y183500D03*
G54D22*
X508583Y86811D03*
X520394D03*
X484960D03*
G54D19*
X17715Y44095D03*
X525590Y240944D03*
X552795Y40157D03*
G54D23*
X359156Y142992D03*
Y208740D03*
%LPD*%
G75*
G54D10*
X15748Y15827D03*
X551181Y242913D03*
G54D11*
X15748Y67008D03*
X303150Y242913D03*
X551181Y13780D03*
G54D12*
X5500Y48299D03*
X7960Y85839D03*
X42701Y5500D03*
X48316Y32530D03*
X44316D03*
Y28681D03*
X48316D03*
X44278Y24717D03*
X48278D03*
X49374Y56390D03*
X45374D03*
X45336Y52426D03*
X49336D03*
X41000Y79500D03*
Y75500D03*
X37000Y79500D03*
Y75500D03*
X49374Y60239D03*
X45374D03*
X27960Y85839D03*
X63713Y48425D03*
X65006Y43434D03*
X67960Y85839D03*
X87960D03*
X107960D03*
X127960D03*
X147960D03*
X167960D03*
X204000Y82000D03*
X208000D03*
Y86000D03*
X204000D03*
X187960Y85839D03*
X261719Y52314D03*
X261774Y48506D03*
X261840Y42259D03*
X261924Y38480D03*
X258240Y42259D03*
X258174Y48506D03*
X258119Y52314D03*
X258324Y38480D03*
X284292Y61505D03*
X280555Y61542D03*
X284798Y149063D03*
X284905Y160541D03*
X284940Y156881D03*
X284798Y152687D03*
X279122Y174213D03*
Y194213D03*
Y214213D03*
Y234213D03*
X282142Y251193D03*
X322701Y5500D03*
X302000Y133500D03*
X301913Y129821D03*
X309500Y145000D03*
X318500Y193500D03*
X314500D03*
X318500Y188500D03*
X314500D03*
X314454Y213250D03*
X314500Y203500D03*
X318500D03*
Y198500D03*
X314500D03*
X322142Y251193D03*
X332778Y20000D03*
X336698Y154738D03*
X340698D03*
X340779Y158381D03*
Y162024D03*
X336779D03*
Y158381D03*
X340779Y165718D03*
X336779D03*
X342142Y251193D03*
X357672Y4602D03*
X347421Y8568D03*
X350479Y10768D03*
X345690Y20300D03*
X353229Y52810D03*
X349229D03*
X353095Y45538D03*
X353094Y49157D03*
X352971Y41813D03*
X349095Y45538D03*
X349094Y49157D03*
X348971Y41813D03*
X354580Y102351D03*
X350569Y102263D03*
X358824Y108849D03*
X352501Y105640D03*
X350827Y108976D03*
X348696Y105396D03*
X356501Y105640D03*
X354827Y108976D03*
X362142Y251193D03*
X382142D03*
X402142D03*
X422142D03*
X442142D03*
X480101Y230616D03*
X462142Y251193D03*
X502868Y166448D03*
X483700Y230522D03*
X502142Y251193D03*
X482142D03*
X519980Y226295D03*
X523642Y226351D03*
X520017Y230070D03*
X523642Y230014D03*
X522142Y251193D03*
X538965Y41992D03*
Y61992D03*
X559461Y68512D03*
Y88512D03*
Y108512D03*
Y148512D03*
Y128512D03*
Y168512D03*
Y188512D03*
Y208512D03*
G54D13*
X93287Y10039D03*
Y54528D03*
X98287Y10039D03*
Y54528D03*
X183287Y10039D03*
X178287D03*
X183287Y54528D03*
X178287D03*
X474331Y137992D03*
X469331D03*
X474331Y203740D03*
X469331D03*
X489331Y137992D03*
Y203740D03*
G54D14*
G01X-139981Y-146685D02*
G02I-12000J0D01*
G01X-145131D02*
G02I-6850J0D01*
G01X-135981D02*
X-167981D01*
G01X-135981Y-162685D02*
Y-242685D01*
G01D02*
X971619D01*
G01X-135981Y-198185D02*
X971619D01*
G01X-151981Y-162685D02*
Y-130685D01*
G01X-135981Y-162685D02*
X971619D01*
G01X184119D02*
Y-242685D01*
G01X178287Y10039D02*
Y13191D01*
G01Y10039D02*
X180766Y12518D01*
G01X183287Y10039D02*
Y13191D01*
G01Y10039D02*
X185766Y12518D01*
G01X178287Y51376D02*
Y54528D01*
G01D02*
Y57680D01*
G01X183287Y51376D02*
Y54528D01*
G01D02*
Y57680D01*
G01X321619Y-162685D02*
Y-242685D01*
G01X436619Y-162685D02*
Y-242685D01*
G01X479958Y86811D02*
X484960D01*
G01X469331Y134840D02*
Y137992D01*
G01D02*
Y141144D01*
G01X474331Y134840D02*
Y137992D01*
G01D02*
Y141144D01*
G01X469331Y200588D02*
Y203740D01*
G01D02*
Y206892D01*
G01X474331Y200588D02*
Y203740D01*
G01D02*
Y206892D01*
G01X484960Y81809D02*
Y86811D01*
G01D02*
Y91813D01*
G01Y86811D02*
X489962D01*
G01X489331Y134840D02*
Y137992D01*
G01D02*
Y141144D01*
G01Y200588D02*
Y203740D01*
G01D02*
Y206892D01*
G01X604119Y-162685D02*
Y-242685D01*
G01X774119Y-162685D02*
Y-242685D01*
G01X971619Y-162685D02*
Y-242685D01*
G01X999619Y-146685D02*
G02I-12000J0D01*
G01X1003619D02*
X971619D01*
G01X994469D02*
G02I-6850J0D01*
G01X987619Y-162685D02*
Y-130685D01*
X268045Y8270D03*
X315166Y52172D03*
X310500Y184328D03*
X340874Y96311D03*
X325404Y101215D03*
X340874Y92311D03*
X329404Y101215D03*
G54D15*
X484960Y86811D03*
G54D16*
G01X63713Y48425D02*
X62663Y47375D01*
Y30663D01*
X77933Y15393D01*
Y10471D01*
X84722Y3682D01*
X216935D01*
X219440Y6187D01*
X221180D01*
X223836Y3531D01*
X276403D01*
X298219Y25347D01*
X309126D01*
X325905Y8568D01*
X347421D01*
G01X65006Y43434D02*
Y31632D01*
X80356Y16282D01*
Y11780D01*
X86254Y5882D01*
X216023D01*
X218528Y8387D01*
X222092D01*
X224748Y5731D01*
X275491D01*
X301899Y32139D01*
X305808D01*
X326756Y11191D01*
X350056D01*
X350479Y10768D01*
G01X309500Y145000D02*
X307839Y146661D01*
Y181667D01*
X310500Y184328D01*
G54D17*
G01X-116181Y-215185D02*
Y-232685D01*
G01X-121203Y-215185D02*
X-111159D01*
G01X-103048Y-232685D02*
Y-215185D01*
X-97808D01*
X-96061Y-216060D01*
X-94751Y-218102D01*
X-94314Y-220435D01*
X-94751Y-222768D01*
X-95843Y-224518D01*
X-97808Y-225394D01*
X-103048D01*
G01X-58878Y-216644D02*
X-60188Y-215768D01*
X-61716Y-215185D01*
X-63463D01*
X-65428Y-216060D01*
X-66956Y-217518D01*
X-68048Y-219269D01*
X-68921Y-222185D01*
X-69140Y-224810D01*
X-68703Y-227435D01*
X-68048Y-229185D01*
X-66738Y-230935D01*
X-65209Y-232102D01*
X-63681Y-232685D01*
X-62153D01*
X-60624Y-232102D01*
X-59314Y-231227D01*
X-58222Y-230061D01*
G01X-49893Y-232685D02*
Y-215185D01*
G01Y-223643D02*
X-48801Y-222185D01*
X-47709Y-221310D01*
X-45963Y-221019D01*
X-44653Y-221310D01*
X-43124Y-222477D01*
X-42469Y-224227D01*
Y-232685D01*
G01X-24751D02*
Y-221019D01*
G01Y-223060D02*
X-25624Y-221894D01*
X-26935Y-221310D01*
X-28463Y-221019D01*
X-29991Y-221602D01*
X-31301Y-222768D01*
X-32175Y-224518D01*
X-32611Y-226852D01*
X-32175Y-229185D01*
X-31301Y-230935D01*
X-29991Y-232102D01*
X-28463Y-232685D01*
X-26935Y-232393D01*
X-25624Y-231519D01*
X-24751Y-230352D01*
G01X-14893Y-232685D02*
Y-221019D01*
G01Y-223935D02*
X-14019Y-222477D01*
X-12709Y-221310D01*
X-10963Y-221019D01*
X-9435Y-221310D01*
X-8124Y-222477D01*
X-7469Y-224518D01*
Y-232685D01*
G01X2607D02*
Y-221019D01*
G01Y-223935D02*
X3481Y-222477D01*
X4791Y-221310D01*
X6537Y-221019D01*
X8065Y-221310D01*
X9376Y-222477D01*
X10031Y-224518D01*
Y-232685D01*
G01X20544Y-224810D02*
X27531D01*
X26876Y-222768D01*
X25784Y-221602D01*
X24256Y-221019D01*
X22727Y-221310D01*
X21417Y-222185D01*
X20544Y-224227D01*
X20107Y-225977D01*
Y-227727D01*
X20544Y-229477D01*
X21636Y-231227D01*
X22946Y-232393D01*
X24474Y-232685D01*
X26002Y-232102D01*
X27531Y-230352D01*
G01X41319Y-232685D02*
Y-215185D01*
G01X71734Y-232685D02*
Y-215185D01*
G01X80904D02*
Y-232685D01*
G01Y-223935D02*
X71734D01*
G01X89016Y-232685D02*
Y-215185D01*
X93382D01*
X95129Y-216060D01*
X96439Y-217227D01*
X97531Y-218976D01*
X98404Y-221019D01*
X98622Y-223935D01*
X98404Y-226852D01*
X97531Y-228894D01*
X96439Y-230644D01*
X95129Y-231810D01*
X93382Y-232685D01*
X89016D01*
G01X106516D02*
Y-215185D01*
X110882D01*
X112629Y-216060D01*
X113939Y-217227D01*
X115031Y-218976D01*
X115904Y-221019D01*
X116122Y-223935D01*
X115904Y-226852D01*
X115031Y-228894D01*
X113939Y-230644D01*
X112629Y-231810D01*
X110882Y-232685D01*
X106516D01*
G01X148065Y-223352D02*
X148939Y-222477D01*
X149594Y-221019D01*
X150031Y-218976D01*
X149594Y-217227D01*
X148721Y-216060D01*
X147192Y-215185D01*
X141297D01*
Y-232685D01*
X148502D01*
X150031Y-231519D01*
X150904Y-229768D01*
X151341Y-227727D01*
X150904Y-225685D01*
X149594Y-223935D01*
X148065Y-223352D01*
X141297D01*
G01X159452Y-232685D02*
Y-215185D01*
X164692D01*
X166439Y-216060D01*
X167749Y-218102D01*
X168186Y-220435D01*
X167749Y-222768D01*
X166657Y-224518D01*
X164692Y-225394D01*
X159452D01*
G01X-16858Y-187685D02*
Y-170185D01*
X-11181Y-184768D01*
X-5504Y-170185D01*
Y-187685D01*
G01X6319D02*
X5009Y-187393D01*
X3699Y-186227D01*
X2825Y-184185D01*
X2389Y-181852D01*
X2825Y-179518D01*
X3699Y-177477D01*
X5009Y-176310D01*
X6319Y-176019D01*
X7629Y-176310D01*
X8939Y-177477D01*
X9812Y-179518D01*
X10031Y-181852D01*
X9812Y-184185D01*
X8939Y-186227D01*
X7629Y-187393D01*
X6319Y-187685D01*
G01X27749Y-170185D02*
Y-187685D01*
G01Y-185061D02*
X26876Y-186519D01*
X25565Y-187393D01*
X24037Y-187685D01*
X22291Y-187102D01*
X20981Y-185644D01*
X20107Y-183894D01*
X19889Y-181852D01*
X20107Y-179810D01*
X20981Y-178060D01*
X22291Y-176602D01*
X24037Y-176019D01*
X25565Y-176310D01*
X26657Y-176894D01*
X27749Y-178060D01*
G01X38044Y-179810D02*
X45031D01*
X44376Y-177768D01*
X43284Y-176602D01*
X41756Y-176019D01*
X40227Y-176310D01*
X38917Y-177185D01*
X38044Y-179227D01*
X37607Y-180977D01*
Y-182727D01*
X38044Y-184477D01*
X39136Y-186227D01*
X40446Y-187393D01*
X41974Y-187685D01*
X43502Y-187102D01*
X45031Y-185352D01*
G01X58819Y-187685D02*
Y-170185D01*
G01X204702Y-187685D02*
Y-170185D01*
X209942D01*
X211689Y-171060D01*
X212999Y-173102D01*
X213436Y-175435D01*
X212999Y-177768D01*
X211907Y-179518D01*
X209942Y-180394D01*
X204702D01*
G01X231372Y-171644D02*
X230062Y-170768D01*
X228534Y-170185D01*
X226787D01*
X224822Y-171060D01*
X223294Y-172518D01*
X222202Y-174269D01*
X221329Y-177185D01*
X221110Y-179810D01*
X221547Y-182435D01*
X222202Y-184185D01*
X223512Y-185935D01*
X225041Y-187102D01*
X226569Y-187685D01*
X228097D01*
X229626Y-187102D01*
X230936Y-186227D01*
X232028Y-185061D01*
G01X245815Y-178352D02*
X246689Y-177477D01*
X247344Y-176019D01*
X247781Y-173976D01*
X247344Y-172227D01*
X246471Y-171060D01*
X244942Y-170185D01*
X239047D01*
Y-187685D01*
X246252D01*
X247781Y-186519D01*
X248654Y-184768D01*
X249091Y-182727D01*
X248654Y-180685D01*
X247344Y-178935D01*
X245815Y-178352D01*
X239047D01*
G01X255019Y-193518D02*
X268119D01*
G01X274047Y-187685D02*
Y-170185D01*
X284091Y-187685D01*
Y-170185D01*
G01X296569Y-187685D02*
X294822Y-187393D01*
X293294Y-186227D01*
X291984Y-184477D01*
X291110Y-182435D01*
X290674Y-180102D01*
Y-177768D01*
X291110Y-175435D01*
X291984Y-173393D01*
X293294Y-171644D01*
X294822Y-170477D01*
X296569Y-170185D01*
X298315Y-170477D01*
X299844Y-171644D01*
X301154Y-173393D01*
X302028Y-175435D01*
X302464Y-177768D01*
Y-180102D01*
X302028Y-182435D01*
X301154Y-184477D01*
X299844Y-186227D01*
X298315Y-187393D01*
X296569Y-187685D01*
G01X217819Y-232685D02*
Y-215185D01*
X215199Y-218685D01*
G01Y-232685D02*
X220439D01*
G01X234882D02*
X235319Y-228894D01*
X235974Y-225685D01*
X236847Y-222768D01*
X237939Y-219560D01*
X239686Y-215185D01*
X230952D01*
G01X248016Y-229185D02*
X249325Y-231227D01*
X251072Y-232393D01*
X253037Y-232685D01*
X254784Y-232393D01*
X256531Y-230935D01*
X257622Y-229185D01*
X257841Y-227435D01*
X257404Y-225394D01*
X255876Y-223935D01*
X254347Y-223352D01*
X252382D01*
G01X254347D02*
X255657Y-222477D01*
X256749Y-221019D01*
X257186Y-219269D01*
X256749Y-217518D01*
X255657Y-216060D01*
X253692Y-215185D01*
X251727Y-215477D01*
X249762Y-216644D01*
G01X270319Y-215185D02*
X268572Y-215768D01*
X267262Y-217227D01*
X266389Y-218976D01*
X265734Y-221310D01*
X265516Y-223935D01*
X265734Y-226560D01*
X266389Y-228894D01*
X267262Y-230644D01*
X268572Y-232102D01*
X270319Y-232685D01*
X272065Y-232102D01*
X273376Y-230644D01*
X274249Y-228894D01*
X274904Y-226560D01*
X275122Y-223935D01*
X274904Y-221310D01*
X274249Y-218976D01*
X273376Y-217227D01*
X272065Y-215768D01*
X270319Y-215185D01*
G01X287819Y-232685D02*
Y-215185D01*
X285199Y-218685D01*
G01Y-232685D02*
X290439D01*
G01X365784Y-230352D02*
X367531Y-231810D01*
X369496Y-232685D01*
X371242D01*
X372989Y-231810D01*
X374299Y-230352D01*
X374954Y-228310D01*
X374517Y-226269D01*
X373426Y-224518D01*
X371461Y-223352D01*
X368841Y-222768D01*
X367312Y-221602D01*
X366657Y-219560D01*
X367094Y-217518D01*
X368186Y-216060D01*
X369714Y-215185D01*
X371242D01*
X372771Y-215768D01*
X374081Y-217227D01*
G01X382410Y-232685D02*
X387869Y-215185D01*
X393328Y-232685D01*
G01X391362Y-226560D02*
X384375D01*
G01X347410Y-170185D02*
X352869Y-187685D01*
X358328Y-170185D01*
G01X374736Y-187685D02*
X366002D01*
Y-170185D01*
X374736D01*
G01X371242Y-178643D02*
X366002D01*
G01X383502Y-187685D02*
Y-170185D01*
X388961D01*
X390707Y-171060D01*
X391799Y-172227D01*
X392236Y-174560D01*
X391799Y-176894D01*
X390489Y-178352D01*
X388961Y-179227D01*
X383502D01*
G01X388961D02*
X392236Y-187685D01*
G01X405369Y-188268D02*
X404932Y-187977D01*
Y-187393D01*
X405369Y-187102D01*
X405806Y-187393D01*
Y-187977D01*
X405369Y-188268D01*
G01X480952Y-170185D02*
Y-187685D01*
X489686D01*
G01X506749D02*
Y-176019D01*
G01Y-178060D02*
X505876Y-176894D01*
X504565Y-176310D01*
X503037Y-176019D01*
X501509Y-176602D01*
X500199Y-177768D01*
X499325Y-179518D01*
X498889Y-181852D01*
X499325Y-184185D01*
X500199Y-185935D01*
X501509Y-187102D01*
X503037Y-187685D01*
X504565Y-187393D01*
X505876Y-186519D01*
X506749Y-185352D01*
G01X515734Y-192935D02*
X517044Y-193518D01*
X518791Y-192935D01*
X519882Y-191769D01*
X520756Y-190310D01*
X522065Y-185644D01*
X524904Y-176019D01*
G01X517917D02*
X522065Y-185644D01*
G01X534544Y-179810D02*
X541531D01*
X540876Y-177768D01*
X539784Y-176602D01*
X538256Y-176019D01*
X536727Y-176310D01*
X535417Y-177185D01*
X534544Y-179227D01*
X534107Y-180977D01*
Y-182727D01*
X534544Y-184477D01*
X535636Y-186227D01*
X536946Y-187393D01*
X538474Y-187685D01*
X540002Y-187102D01*
X541531Y-185352D01*
G01X552262Y-187685D02*
Y-176019D01*
G01Y-178352D02*
X553354Y-177185D01*
X554446Y-176310D01*
X555974Y-176019D01*
X557065Y-176310D01*
X558376Y-177185D01*
G01X507202Y-215185D02*
Y-232685D01*
X515936D01*
G01X524266Y-229185D02*
X525575Y-231227D01*
X527322Y-232393D01*
X529287Y-232685D01*
X531034Y-232393D01*
X532781Y-230935D01*
X533872Y-229185D01*
X534091Y-227435D01*
X533654Y-225394D01*
X532126Y-223935D01*
X530597Y-223352D01*
X528632D01*
G01X530597D02*
X531907Y-222477D01*
X532999Y-221019D01*
X533436Y-219269D01*
X532999Y-217518D01*
X531907Y-216060D01*
X529942Y-215185D01*
X527977Y-215477D01*
X526012Y-216644D01*
G01X623066Y-187685D02*
Y-170185D01*
X627432D01*
X629179Y-171060D01*
X630489Y-172227D01*
X631581Y-173976D01*
X632454Y-176019D01*
X632672Y-178935D01*
X632454Y-181852D01*
X631581Y-183894D01*
X630489Y-185644D01*
X629179Y-186810D01*
X627432Y-187685D01*
X623066D01*
G01X642094Y-179810D02*
X649081D01*
X648426Y-177768D01*
X647334Y-176602D01*
X645806Y-176019D01*
X644277Y-176310D01*
X642967Y-177185D01*
X642094Y-179227D01*
X641657Y-180977D01*
Y-182727D01*
X642094Y-184477D01*
X643186Y-186227D01*
X644496Y-187393D01*
X646024Y-187685D01*
X647552Y-187102D01*
X649081Y-185352D01*
G01X659594Y-185644D02*
X660686Y-186810D01*
X662214Y-187685D01*
X663524D01*
X664834Y-187102D01*
X665707Y-186227D01*
X666144Y-185061D01*
X665926Y-183310D01*
X665052Y-182435D01*
X661122Y-180685D01*
X660249Y-178643D01*
X660686Y-177185D01*
X661559Y-176310D01*
X662869Y-176019D01*
X664179Y-176310D01*
X665489Y-177185D01*
G01X680369Y-176019D02*
Y-187685D01*
G01Y-171352D02*
X679932Y-171060D01*
Y-170477D01*
X680369Y-170185D01*
X680806Y-170477D01*
Y-171060D01*
X680369Y-171352D01*
G01X694812Y-192060D02*
X696341Y-193227D01*
X698087Y-193518D01*
X699615Y-193227D01*
X700926Y-191769D01*
X701799Y-189727D01*
Y-176019D01*
G01Y-178352D02*
X700926Y-177185D01*
X699615Y-176310D01*
X698087Y-176019D01*
X696341Y-176602D01*
X695249Y-177768D01*
X694375Y-179810D01*
X693939Y-181852D01*
X694157Y-183602D01*
X695031Y-185644D01*
X696341Y-187102D01*
X698087Y-187685D01*
X699397Y-187393D01*
X700926Y-186227D01*
X701799Y-185061D01*
G01X711657Y-187685D02*
Y-176019D01*
G01Y-178935D02*
X712531Y-177477D01*
X713841Y-176310D01*
X715587Y-176019D01*
X717115Y-176310D01*
X718426Y-177477D01*
X719081Y-179518D01*
Y-187685D01*
G01X729594Y-179810D02*
X736581D01*
X735926Y-177768D01*
X734834Y-176602D01*
X733306Y-176019D01*
X731777Y-176310D01*
X730467Y-177185D01*
X729594Y-179227D01*
X729157Y-180977D01*
Y-182727D01*
X729594Y-184477D01*
X730686Y-186227D01*
X731996Y-187393D01*
X733524Y-187685D01*
X735052Y-187102D01*
X736581Y-185352D01*
G01X747312Y-187685D02*
Y-176019D01*
G01Y-178352D02*
X748404Y-177185D01*
X749496Y-176310D01*
X751024Y-176019D01*
X752115Y-176310D01*
X753426Y-177185D01*
G01X664179Y-223935D02*
X668546D01*
Y-229185D01*
X667236Y-230935D01*
X665707Y-232102D01*
X663524Y-232685D01*
X661341Y-232102D01*
X659812Y-230935D01*
X658502Y-229185D01*
X657629Y-227143D01*
X657192Y-224810D01*
Y-222768D01*
X657629Y-221019D01*
X658502Y-218976D01*
X659812Y-217227D01*
X661122Y-216060D01*
X662869Y-215185D01*
X664397D01*
X666144Y-215768D01*
X667454Y-216935D01*
G01X684736Y-232685D02*
X676002D01*
Y-215185D01*
X684736D01*
G01X681242Y-223643D02*
X676002D01*
G01X693502Y-215185D02*
Y-232685D01*
X702236D01*
G01X715369D02*
X713622Y-232393D01*
X712094Y-231227D01*
X710784Y-229477D01*
X709910Y-227435D01*
X709474Y-225102D01*
Y-222768D01*
X709910Y-220435D01*
X710784Y-218393D01*
X712094Y-216644D01*
X713622Y-215477D01*
X715369Y-215185D01*
X717115Y-215477D01*
X718644Y-216644D01*
X719954Y-218393D01*
X720828Y-220435D01*
X721264Y-222768D01*
Y-225102D01*
X720828Y-227435D01*
X719954Y-229477D01*
X718644Y-231227D01*
X717115Y-232393D01*
X715369Y-232685D01*
G01X794069Y-215185D02*
X792322Y-215768D01*
X791012Y-217227D01*
X790139Y-218976D01*
X789484Y-221310D01*
X789266Y-223935D01*
X789484Y-226560D01*
X790139Y-228894D01*
X791012Y-230644D01*
X792322Y-232102D01*
X794069Y-232685D01*
X795815Y-232102D01*
X797126Y-230644D01*
X797999Y-228894D01*
X798654Y-226560D01*
X798872Y-223935D01*
X798654Y-221310D01*
X797999Y-218976D01*
X797126Y-217227D01*
X795815Y-215768D01*
X794069Y-215185D01*
G01X807421Y-225394D02*
X808949Y-223352D01*
X810259Y-222185D01*
X812006Y-221602D01*
X813534Y-222185D01*
X814626Y-223352D01*
X815499Y-225102D01*
X815717Y-227143D01*
X815499Y-228894D01*
X814626Y-230644D01*
X813315Y-232102D01*
X811787Y-232685D01*
X810041Y-232102D01*
X808512Y-230352D01*
X807639Y-227727D01*
X807421Y-224810D01*
X807857Y-221019D01*
X808512Y-218976D01*
X809604Y-216935D01*
X811132Y-215477D01*
X812661Y-215185D01*
X814189Y-215768D01*
X815281Y-217227D01*
G01X825139Y-233268D02*
X832999Y-215185D01*
G01X842421Y-218102D02*
X843731Y-216352D01*
X845259Y-215477D01*
X847006Y-215185D01*
X849189Y-215768D01*
X850717Y-217227D01*
X851154Y-218976D01*
X850936Y-220727D01*
X850062Y-222185D01*
X845696Y-225102D01*
X843731Y-227143D01*
X842421Y-230061D01*
X841984Y-232685D01*
X851154D01*
G01X859921Y-218102D02*
X861231Y-216352D01*
X862759Y-215477D01*
X864506Y-215185D01*
X866689Y-215768D01*
X868217Y-217227D01*
X868654Y-218976D01*
X868436Y-220727D01*
X867562Y-222185D01*
X863196Y-225102D01*
X861231Y-227143D01*
X859921Y-230061D01*
X859484Y-232685D01*
X868654D01*
G01X877639Y-233268D02*
X885499Y-215185D01*
G01X894921Y-218102D02*
X896231Y-216352D01*
X897759Y-215477D01*
X899506Y-215185D01*
X901689Y-215768D01*
X903217Y-217227D01*
X903654Y-218976D01*
X903436Y-220727D01*
X902562Y-222185D01*
X898196Y-225102D01*
X896231Y-227143D01*
X894921Y-230061D01*
X894484Y-232685D01*
X903654D01*
G01X916569Y-215185D02*
X914822Y-215768D01*
X913512Y-217227D01*
X912639Y-218976D01*
X911984Y-221310D01*
X911766Y-223935D01*
X911984Y-226560D01*
X912639Y-228894D01*
X913512Y-230644D01*
X914822Y-232102D01*
X916569Y-232685D01*
X918315Y-232102D01*
X919626Y-230644D01*
X920499Y-228894D01*
X921154Y-226560D01*
X921372Y-223935D01*
X921154Y-221310D01*
X920499Y-218976D01*
X919626Y-217227D01*
X918315Y-215768D01*
X916569Y-215185D01*
G01X934069Y-232685D02*
Y-215185D01*
X931449Y-218685D01*
G01Y-232685D02*
X936689D01*
G01X951132D02*
X951569Y-228894D01*
X952224Y-225685D01*
X953097Y-222768D01*
X954189Y-219560D01*
X955936Y-215185D01*
X947202D01*
G01X841766Y-187685D02*
Y-170185D01*
X846132D01*
X847879Y-171060D01*
X849189Y-172227D01*
X850281Y-173976D01*
X851154Y-176019D01*
X851372Y-178935D01*
X851154Y-181852D01*
X850281Y-183894D01*
X849189Y-185644D01*
X847879Y-186810D01*
X846132Y-187685D01*
X841766D01*
G01X867999D02*
Y-176019D01*
G01Y-178060D02*
X867126Y-176894D01*
X865815Y-176310D01*
X864287Y-176019D01*
X862759Y-176602D01*
X861449Y-177768D01*
X860575Y-179518D01*
X860139Y-181852D01*
X860575Y-184185D01*
X861449Y-185935D01*
X862759Y-187102D01*
X864287Y-187685D01*
X865815Y-187393D01*
X867126Y-186519D01*
X867999Y-185352D01*
G01X881569Y-170185D02*
Y-187685D01*
G01X878512Y-176019D02*
X884626D01*
G01X895794Y-179810D02*
X902781D01*
X902126Y-177768D01*
X901034Y-176602D01*
X899506Y-176019D01*
X897977Y-176310D01*
X896667Y-177185D01*
X895794Y-179227D01*
X895357Y-180977D01*
Y-182727D01*
X895794Y-184477D01*
X896886Y-186227D01*
X898196Y-187393D01*
X899724Y-187685D01*
X901252Y-187102D01*
X902781Y-185352D01*
G54D18*
G01X93287Y10039D02*
X95135Y11887D01*
Y12990D01*
X91974Y16151D01*
X75472Y41074D01*
X74830Y44245D01*
X75537Y47710D01*
X79999Y54454D01*
X92055Y62434D01*
X111031Y66293D01*
X124831Y63485D01*
X131625Y64868D01*
X140720Y63017D01*
X218462Y78834D01*
X220978Y80499D01*
X308344Y98274D01*
X320219Y106134D01*
X322848Y106667D01*
X325003Y106231D01*
X327008Y104904D01*
X327840Y103646D01*
X328034Y102694D01*
Y101775D01*
X328594Y101215D01*
X329404D01*
G01X98287Y10039D02*
X96395Y11931D01*
Y13512D01*
X92955Y16952D01*
X76659Y41565D01*
X76116Y44244D01*
X76723Y47218D01*
X80909Y53544D01*
X92547Y61247D01*
X111031Y65007D01*
X124831Y62199D01*
X131625Y63582D01*
X140720Y61731D01*
X218953Y77648D01*
X221469Y79313D01*
X226742Y80385D01*
X227568Y79839D01*
X229214Y80174D01*
X229761Y80999D01*
X231407Y81334D01*
X232232Y80788D01*
X233878Y81123D01*
X234425Y81948D01*
X236071Y82283D01*
X236896Y81737D01*
X238542Y82072D01*
X239089Y82897D01*
X240735Y83232D01*
X241561Y82685D01*
X243207Y83020D01*
X243753Y83846D01*
X258887Y86924D01*
X259712Y86378D01*
X261358Y86713D01*
X261905Y87538D01*
X263551Y87873D01*
X264376Y87327D01*
X266022Y87662D01*
X266569Y88487D01*
X268215Y88822D01*
X269040Y88276D01*
X270686Y88611D01*
X271233Y89436D01*
X272879Y89771D01*
X273705Y89225D01*
X275351Y89560D01*
X275897Y90385D01*
X290180Y93291D01*
X291005Y92745D01*
X292651Y93080D01*
X293198Y93905D01*
X294844Y94240D01*
X295669Y93694D01*
X297315Y94029D01*
X297862Y94854D01*
X299508Y95189D01*
X300333Y94643D01*
X301979Y94978D01*
X302526Y95803D01*
X304172Y96138D01*
X304997Y95592D01*
X306643Y95927D01*
X307190Y96752D01*
X308836Y97087D01*
X308835Y97088D01*
X320710Y104947D01*
X322848Y105381D01*
X324512Y105044D01*
X326098Y103994D01*
X326654Y103154D01*
X326774Y102567D01*
Y101775D01*
X326214Y101215D01*
X325404D01*
G01X93287Y54528D02*
X95305Y56546D01*
Y57941D01*
X96396Y59277D01*
X110361Y62113D01*
X123869Y59364D01*
X130801Y60774D01*
X140927Y58715D01*
X213884Y73555D01*
X253425Y65512D01*
Y65511D01*
X305461Y76097D01*
X322357Y72660D01*
X326540Y73511D01*
X327087Y74336D01*
X328733Y74671D01*
X329559Y74124D01*
X331205Y74459D01*
X331752Y75285D01*
X333398Y75620D01*
X334224Y75073D01*
X335870Y75408D01*
X336416Y76234D01*
X338062Y76569D01*
X338888Y76022D01*
X340534Y76357D01*
X344537Y79007D01*
X347309Y83195D01*
X348284Y87981D01*
X347442Y92108D01*
X344891Y93798D01*
X342361D01*
X340874Y92311D01*
G01X98287Y54528D02*
X96565Y56250D01*
Y57491D01*
X97088Y58131D01*
X110361Y60827D01*
X123869Y58078D01*
X130801Y59488D01*
X140927Y57429D01*
X213884Y72269D01*
X253425Y64225D01*
X305461Y74811D01*
X322357Y71374D01*
X341026Y75170D01*
X345447Y78097D01*
X348496Y82703D01*
X349570Y87981D01*
X348573Y92871D01*
X345271Y95058D01*
X342127D01*
X340874Y96311D01*
M02*
